(kicad_pcb
	(version 20260206)
	(generator "pcbnew")
	(generator_version "10.0")
	(general
		(thickness 1.6)
		(legacy_teardrops no)
	)
	(paper "A4")
	(title_block
		(title "12092022_DA0F0TFB6D0_F0T_FAN_BOARD_MP5048_D_brd_v02_OCP.brd")
		(comment 1 "Grand Teton / footprints 692-697 of 924")
	)
	(layers
		(0 "F.Cu" signal "TOP")
		(4 "In1.Cu" signal "GND")
		(6 "In2.Cu" signal "IN1")
		(8 "In3.Cu" signal "IN2")
		(10 "In4.Cu" signal "GND1")
		(2 "B.Cu" signal "BOTTOM")
		(9 "F.Adhes" user "F.Adhesive")
		(11 "B.Adhes" user "B.Adhesive")
		(13 "F.Paste" user "Package Geometry/Pastemask Top")
		(15 "B.Paste" user "Package Geometry/Pastemask Bottom")
		(5 "F.SilkS" user "Ref Des/Silkscreen Top")
		(7 "B.SilkS" user "Ref Des/Silkscreen Bottom")
		(1 "F.Mask" user "Board Geometry/Soldermask Top")
		(3 "B.Mask" user "Board Geometry/Soldermask Bottom")
		(17 "Dwgs.User" user "User.Drawings")
		(19 "Cmts.User" user "User.Comments")
		(21 "Eco1.User" user "User.Eco1")
		(23 "Eco2.User" user "User.Eco2")
		(25 "Edge.Cuts" user "Board Geometry/Outline")
		(27 "Margin" user)
		(31 "F.CrtYd" user "Package Geometry/Place Bound Top")
		(29 "B.CrtYd" user "Package Geometry/Place Bound Bottom")
		(35 "F.Fab" user "Ref Des/Assembly Top")
		(33 "B.Fab" user "Ref Des/Assembly Bottom")
	)
	(footprint ""
		(layer "F.Cu")
		(at 42.291 -258.445 180)
		(property "Reference" "PR1"
			(at 0 0 180)
			(layer "F.SilkS")
			(hide yes)
			(effects
				(font
					(size 1.27 1.27)
				)
			)
		)
		(property "Value" ""
			(at 0 0 180)
			(layer "F.Fab")
			(effects
				(font
					(size 1.27 1.27)
				)
			)
		)
		(duplicate_pad_numbers_are_jumpers no)
		(fp_line
			(start 0.7874 0.4064)
			(end -0.7874 0.4064)
			(stroke
				(width 0.1524)
				(type default)
			)
			(layer "F.SilkS")
		)
		(fp_line
			(start 0.7874 -0.4064)
			(end 0.7874 0.4064)
			(stroke
				(width 0.1524)
				(type default)
			)
			(layer "F.SilkS")
		)
		(fp_line
			(start -0.7874 0.4064)
			(end -0.7874 -0.4064)
			(stroke
				(width 0.1524)
				(type default)
			)
			(layer "F.SilkS")
		)
		(fp_line
			(start -0.7874 -0.4064)
			(end 0.7874 -0.4064)
			(stroke
				(width 0.1524)
				(type default)
			)
			(layer "F.SilkS")
		)
		(fp_line
			(start 0.67945 0.3048)
			(end 0.120396 0.3048)
			(stroke
				(width 0.1)
				(type default)
			)
			(layer "F.Fab")
		)
		(fp_line
			(start 0.67945 -0.3048)
			(end 0.67945 0.3048)
			(stroke
				(width 0.1)
				(type default)
			)
			(layer "F.Fab")
		)
		(fp_line
			(start 0.12065 -0.2794)
			(end 0.12065 -0.3048)
			(stroke
				(width 0.1)
				(type default)
			)
			(layer "F.Fab")
		)
		(fp_line
			(start 0.12065 -0.3048)
			(end 0.67945 -0.3048)
			(stroke
				(width 0.1)
				(type default)
			)
			(layer "F.Fab")
		)
		(fp_line
			(start 0.120396 0.3048)
			(end 0.120396 0.2794)
			(stroke
				(width 0.1)
				(type default)
			)
			(layer "F.Fab")
		)
		(fp_line
			(start 0.120396 0.2794)
			(end -0.12065 0.2794)
			(stroke
				(width 0.1)
				(type default)
			)
			(layer "F.Fab")
		)
		(fp_line
			(start -0.12065 0.3048)
			(end -0.67945 0.3048)
			(stroke
				(width 0.1)
				(type default)
			)
			(layer "F.Fab")
		)
		(fp_line
			(start -0.12065 0.2794)
			(end -0.12065 0.3048)
			(stroke
				(width 0.1)
				(type default)
			)
			(layer "F.Fab")
		)
		(fp_line
			(start -0.12065 -0.2794)
			(end 0.12065 -0.2794)
			(stroke
				(width 0.1)
				(type default)
			)
			(layer "F.Fab")
		)
		(fp_line
			(start -0.12065 -0.305054)
			(end -0.12065 -0.2794)
			(stroke
				(width 0.1)
				(type default)
			)
			(layer "F.Fab")
		)
		(fp_line
			(start -0.67945 0.3048)
			(end -0.67945 -0.305054)
			(stroke
				(width 0.1)
				(type default)
			)
			(layer "F.Fab")
		)
		(fp_line
			(start -0.67945 -0.305054)
			(end -0.12065 -0.305054)
			(stroke
				(width 0.1)
				(type default)
			)
			(layer "F.Fab")
		)
		(pad "1" smd circle
			(at -0.40005 0 180)
			(size 0 0)
			(layers "F.Cu" "F.Mask" "F.Paste")
			(net "FAN_0_FAULT_R")
		)
		(pad "2" smd circle
			(at 0.40005 0 180)
			(size 0 0)
			(layers "F.Cu" "F.Mask" "F.Paste")
			(net "FAN_0_P3V_R")
		)
	)
	(footprint ""
		(layer "F.Cu")
		(at 28.956 -173.609 180)
		(property "Reference" "R5107"
			(at 0 0 180)
			(layer "F.SilkS")
			(hide yes)
			(effects
				(font
					(size 1.27 1.27)
				)
			)
		)
		(property "Value" ""
			(at 0 0 180)
			(layer "F.Fab")
			(effects
				(font
					(size 1.27 1.27)
				)
			)
		)
		(duplicate_pad_numbers_are_jumpers no)
		(fp_line
			(start 0.7874 0.4064)
			(end -0.7874 0.4064)
			(stroke
				(width 0.1524)
				(type default)
			)
			(layer "F.SilkS")
		)
		(fp_line
			(start 0.7874 -0.4064)
			(end 0.7874 0.4064)
			(stroke
				(width 0.1524)
				(type default)
			)
			(layer "F.SilkS")
		)
		(fp_line
			(start -0.7874 0.4064)
			(end -0.7874 -0.4064)
			(stroke
				(width 0.1524)
				(type default)
			)
			(layer "F.SilkS")
		)
		(fp_line
			(start -0.7874 -0.4064)
			(end 0.7874 -0.4064)
			(stroke
				(width 0.1524)
				(type default)
			)
			(layer "F.SilkS")
		)
		(fp_line
			(start 0.67945 0.3048)
			(end 0.120396 0.3048)
			(stroke
				(width 0.1)
				(type default)
			)
			(layer "F.Fab")
		)
		(fp_line
			(start 0.67945 -0.3048)
			(end 0.67945 0.3048)
			(stroke
				(width 0.1)
				(type default)
			)
			(layer "F.Fab")
		)
		(fp_line
			(start 0.12065 -0.2794)
			(end 0.12065 -0.3048)
			(stroke
				(width 0.1)
				(type default)
			)
			(layer "F.Fab")
		)
		(fp_line
			(start 0.12065 -0.3048)
			(end 0.67945 -0.3048)
			(stroke
				(width 0.1)
				(type default)
			)
			(layer "F.Fab")
		)
		(fp_line
			(start 0.120396 0.3048)
			(end 0.120396 0.2794)
			(stroke
				(width 0.1)
				(type default)
			)
			(layer "F.Fab")
		)
		(fp_line
			(start 0.120396 0.2794)
			(end -0.12065 0.2794)
			(stroke
				(width 0.1)
				(type default)
			)
			(layer "F.Fab")
		)
		(fp_line
			(start -0.12065 0.3048)
			(end -0.67945 0.3048)
			(stroke
				(width 0.1)
				(type default)
			)
			(layer "F.Fab")
		)
		(fp_line
			(start -0.12065 0.2794)
			(end -0.12065 0.3048)
			(stroke
				(width 0.1)
				(type default)
			)
			(layer "F.Fab")
		)
		(fp_line
			(start -0.12065 -0.2794)
			(end 0.12065 -0.2794)
			(stroke
				(width 0.1)
				(type default)
			)
			(layer "F.Fab")
		)
		(fp_line
			(start -0.12065 -0.305054)
			(end -0.12065 -0.2794)
			(stroke
				(width 0.1)
				(type default)
			)
			(layer "F.Fab")
		)
		(fp_line
			(start -0.67945 0.3048)
			(end -0.67945 -0.305054)
			(stroke
				(width 0.1)
				(type default)
			)
			(layer "F.Fab")
		)
		(fp_line
			(start -0.67945 -0.305054)
			(end -0.12065 -0.305054)
			(stroke
				(width 0.1)
				(type default)
			)
			(layer "F.Fab")
		)
		(pad "1" smd circle
			(at -0.40005 0 180)
			(size 0 0)
			(layers "F.Cu" "F.Mask" "F.Paste")
			(net "FAN_6_OK_LED")
		)
		(pad "2" smd circle
			(at 0.40005 0 180)
			(size 0 0)
			(layers "F.Cu" "F.Mask" "F.Paste")
			(net "FAN_6_OK_R_LED")
		)
	)
	(footprint ""
		(layer "F.Cu")
		(at 35.2806 -90.9574 180)
		(property "Reference" "PC29"
			(at -2.413 -5.94487 0)
			(unlocked yes)
			(layer "F.SilkS")
			(effects
				(font
					(size 0.7874 0.5842)
					(thickness 0.1524)
				)
				(justify left)
			)
		)
		(property "Value" ""
			(at 0 0 180)
			(layer "F.Fab")
			(effects
				(font
					(size 1.27 1.27)
				)
			)
		)
		(duplicate_pad_numbers_are_jumpers no)
		(fp_line
			(start 5.249926 5.249926)
			(end 5.249926 1.2446)
			(stroke
				(width 0.1524)
				(type default)
			)
			(layer "F.SilkS")
		)
		(fp_line
			(start 5.249926 -1.2446)
			(end 5.249926 -5.249926)
			(stroke
				(width 0.1524)
				(type default)
			)
			(layer "F.SilkS")
		)
		(fp_line
			(start 5.249926 -5.249926)
			(end -3.979926 -5.249926)
			(stroke
				(width 0.1524)
				(type default)
			)
			(layer "F.SilkS")
		)
		(fp_line
			(start -3.979926 5.249926)
			(end 5.249926 5.249926)
			(stroke
				(width 0.1524)
				(type default)
			)
			(layer "F.SilkS")
		)
		(fp_line
			(start -3.979926 -5.249926)
			(end -5.249926 -3.979926)
			(stroke
				(width 0.1524)
				(type default)
			)
			(layer "F.SilkS")
		)
		(fp_line
			(start -5.249926 3.979926)
			(end -3.979926 5.249926)
			(stroke
				(width 0.1524)
				(type default)
			)
			(layer "F.SilkS")
		)
		(fp_line
			(start -5.249926 1.2446)
			(end -5.249926 3.979926)
			(stroke
				(width 0.1524)
				(type default)
			)
			(layer "F.SilkS")
		)
		(fp_line
			(start -5.249926 -3.979926)
			(end -5.249926 -1.2446)
			(stroke
				(width 0.1524)
				(type default)
			)
			(layer "F.SilkS")
		)
		(fp_line
			(start 5.249926 5.249926)
			(end 5.249926 -5.249926)
			(stroke
				(width 0.1)
				(type default)
			)
			(layer "F.Fab")
		)
		(fp_line
			(start 5.249926 -5.249926)
			(end -5.249926 -5.249926)
			(stroke
				(width 0.1)
				(type default)
			)
			(layer "F.Fab")
		)
		(fp_line
			(start -5.249926 5.249926)
			(end 5.249926 5.249926)
			(stroke
				(width 0.1)
				(type default)
			)
			(layer "F.Fab")
		)
		(fp_line
			(start -5.249926 -5.249926)
			(end -5.249926 5.249926)
			(stroke
				(width 0.1)
				(type default)
			)
			(layer "F.Fab")
		)
		(pad "1" smd rect
			(at -4.45008 0 270)
			(size 2.2098 4.4196)
			(layers "F.Cu" "F.Mask" "F.Paste")
			(net "P52V_FAN_2")
		)
		(pad "2" smd rect
			(at 4.45008 0 270)
			(size 2.2098 4.4196)
			(layers "F.Cu" "F.Mask" "F.Paste")
			(net "GND")
		)
	)
	(footprint ""
		(layer "F.Cu")
		(at 42.418 -73.66 90)
		(property "Reference" "PR36"
			(at 0 0 90)
			(layer "F.SilkS")
			(hide yes)
			(effects
				(font
					(size 1.27 1.27)
				)
			)
		)
		(property "Value" ""
			(at 0 0 90)
			(layer "F.Fab")
			(effects
				(font
					(size 1.27 1.27)
				)
			)
		)
		(duplicate_pad_numbers_are_jumpers no)
		(fp_line
			(start 0.7874 -0.4064)
			(end 0.7874 0.4064)
			(stroke
				(width 0.1524)
				(type default)
			)
			(layer "F.SilkS")
		)
		(fp_line
			(start -0.7874 -0.4064)
			(end 0.7874 -0.4064)
			(stroke
				(width 0.1524)
				(type default)
			)
			(layer "F.SilkS")
		)
		(fp_line
			(start 0.7874 0.4064)
			(end -0.7874 0.4064)
			(stroke
				(width 0.1524)
				(type default)
			)
			(layer "F.SilkS")
		)
		(fp_line
			(start -0.7874 0.4064)
			(end -0.7874 -0.4064)
			(stroke
				(width 0.1524)
				(type default)
			)
			(layer "F.SilkS")
		)
		(fp_line
			(start -0.12065 -0.305054)
			(end -0.12065 -0.2794)
			(stroke
				(width 0.1)
				(type default)
			)
			(layer "F.Fab")
		)
		(fp_line
			(start -0.67945 -0.305054)
			(end -0.12065 -0.305054)
			(stroke
				(width 0.1)
				(type default)
			)
			(layer "F.Fab")
		)
		(fp_line
			(start 0.67945 -0.3048)
			(end 0.67945 0.3048)
			(stroke
				(width 0.1)
				(type default)
			)
			(layer "F.Fab")
		)
		(fp_line
			(start 0.12065 -0.3048)
			(end 0.67945 -0.3048)
			(stroke
				(width 0.1)
				(type default)
			)
			(layer "F.Fab")
		)
		(fp_line
			(start 0.12065 -0.2794)
			(end 0.12065 -0.3048)
			(stroke
				(width 0.1)
				(type default)
			)
			(layer "F.Fab")
		)
		(fp_line
			(start -0.12065 -0.2794)
			(end 0.12065 -0.2794)
			(stroke
				(width 0.1)
				(type default)
			)
			(layer "F.Fab")
		)
		(fp_line
			(start 0.120396 0.2794)
			(end -0.12065 0.2794)
			(stroke
				(width 0.1)
				(type default)
			)
			(layer "F.Fab")
		)
		(fp_line
			(start -0.12065 0.2794)
			(end -0.12065 0.3048)
			(stroke
				(width 0.1)
				(type default)
			)
			(layer "F.Fab")
		)
		(fp_line
			(start 0.67945 0.3048)
			(end 0.120396 0.3048)
			(stroke
				(width 0.1)
				(type default)
			)
			(layer "F.Fab")
		)
		(fp_line
			(start 0.120396 0.3048)
			(end 0.120396 0.2794)
			(stroke
				(width 0.1)
				(type default)
			)
			(layer "F.Fab")
		)
		(fp_line
			(start -0.12065 0.3048)
			(end -0.67945 0.3048)
			(stroke
				(width 0.1)
				(type default)
			)
			(layer "F.Fab")
		)
		(fp_line
			(start -0.67945 0.3048)
			(end -0.67945 -0.305054)
			(stroke
				(width 0.1)
				(type default)
			)
			(layer "F.Fab")
		)
		(pad "1" smd rect
			(at -0.40005 0 270)
			(size 0.4572 0.508)
			(layers "F.Cu" "F.Mask" "F.Paste")
			(net "FAN_2_FAULT_R")
		)
		(pad "2" smd rect
			(at 0.40005 0 270)
			(size 0.4572 0.508)
			(layers "F.Cu" "F.Mask" "F.Paste")
			(net "FAN_2_FAULT")
		)
	)
	(footprint ""
		(layer "F.Cu")
		(at 36.322 -117.602)
		(property "Reference" "D137"
			(at 2.96926 -0.13843 0)
			(unlocked yes)
			(layer "F.SilkS")
			(effects
				(font
					(size 0.635 0.4064)
					(thickness 0.1524)
				)
				(justify left)
			)
		)
		(property "Value" ""
			(at 0 0 0)
			(layer "F.Fab")
			(effects
				(font
					(size 1.27 1.27)
				)
			)
		)
		(duplicate_pad_numbers_are_jumpers no)
		(fp_line
			(start -0.299974 -0.500126)
			(end -0.299974 0.500126)
			(stroke
				(width 0.1524)
				(type default)
			)
			(layer "F.SilkS")
		)
		(fp_line
			(start -0.299974 0.500126)
			(end 0.199898 0)
			(stroke
				(width 0.1524)
				(type default)
			)
			(layer "F.SilkS")
		)
		(fp_line
			(start 0.199898 0)
			(end -0.299974 -0.500126)
			(stroke
				(width 0.1524)
				(type default)
			)
			(layer "F.SilkS")
		)
		(fp_line
			(start 0.299974 -0.500126)
			(end 0.299974 0.500126)
			(stroke
				(width 0.1524)
				(type default)
			)
			(layer "F.SilkS")
		)
		(fp_line
			(start 1.651 -0.6858)
			(end 1.651 0.6858)
			(stroke
				(width 0.1524)
				(type default)
			)
			(layer "F.SilkS")
		)
		(fp_line
			(start 1.778 0.6858)
			(end 1.778 -0.6858)
			(stroke
				(width 0.1524)
				(type default)
			)
			(layer "F.SilkS")
		)
		(fp_line
			(start -1.35001 -0.225044)
			(end -0.899922 -0.225044)
			(stroke
				(width 0.1)
				(type default)
			)
			(layer "F.Fab")
		)
		(fp_line
			(start -1.35001 0.175006)
			(end -1.35001 -0.225044)
			(stroke
				(width 0.1)
				(type default)
			)
			(layer "F.Fab")
		)
		(fp_line
			(start -0.899922 -0.700024)
			(end 0.899922 -0.700024)
			(stroke
				(width 0.1)
				(type default)
			)
			(layer "F.Fab")
		)
		(fp_line
			(start -0.899922 -0.225044)
			(end -0.899922 -0.700024)
			(stroke
				(width 0.1)
				(type default)
			)
			(layer "F.Fab")
		)
		(fp_line
			(start -0.899922 0.175006)
			(end -1.35001 0.175006)
			(stroke
				(width 0.1)
				(type default)
			)
			(layer "F.Fab")
		)
		(fp_line
			(start -0.899922 0.700024)
			(end -0.899922 0.175006)
			(stroke
				(width 0.1)
				(type default)
			)
			(layer "F.Fab")
		)
		(fp_line
			(start -0.299974 -0.500126)
			(end -0.299974 0.500126)
			(stroke
				(width 0.1)
				(type default)
			)
			(layer "F.Fab")
		)
		(fp_line
			(start -0.299974 0.500126)
			(end 0.199898 0)
			(stroke
				(width 0.1)
				(type default)
			)
			(layer "F.Fab")
		)
		(fp_line
			(start 0.199898 0)
			(end -0.299974 -0.500126)
			(stroke
				(width 0.1)
				(type default)
			)
			(layer "F.Fab")
		)
		(fp_line
			(start 0.299974 -0.500126)
			(end 0.299974 0.500126)
			(stroke
				(width 0.1)
				(type default)
			)
			(layer "F.Fab")
		)
		(fp_line
			(start 0.899922 -0.700024)
			(end 0.899922 -0.225044)
			(stroke
				(width 0.1)
				(type default)
			)
			(layer "F.Fab")
		)
		(fp_line
			(start 0.899922 -0.225044)
			(end 1.35001 -0.225044)
			(stroke
				(width 0.1)
				(type default)
			)
			(layer "F.Fab")
		)
		(fp_line
			(start 0.899922 0.175006)
			(end 0.899922 0.700024)
			(stroke
				(width 0.1)
				(type default)
			)
			(layer "F.Fab")
		)
		(fp_line
			(start 0.899922 0.700024)
			(end -0.899922 0.700024)
			(stroke
				(width 0.1)
				(type default)
			)
			(layer "F.Fab")
		)
		(fp_line
			(start 1.35001 -0.225044)
			(end 1.35001 0.175006)
			(stroke
				(width 0.1)
				(type default)
			)
			(layer "F.Fab")
		)
		(fp_line
			(start 1.35001 0.175006)
			(end 0.899922 0.175006)
			(stroke
				(width 0.1)
				(type default)
			)
			(layer "F.Fab")
		)
		(fp_text user "+"
			(at -2.667 0.79375 0)
			(unlocked yes)
			(layer "F.SilkS")
			(effects
				(font
					(size 1.905 1.4224)
					(thickness 0.1524)
				)
				(justify left)
			)
		)
		(fp_text user "-"
			(at 0.508 -1.23825 0)
			(unlocked yes)
			(layer "F.SilkS")
			(effects
				(font
					(size 1.905 1.4224)
					(thickness 0.1524)
				)
				(justify left)
			)
		)
		(fp_text user "+"
			(at -2.794 -0.19685 0)
			(unlocked yes)
			(layer "F.Fab")
			(effects
				(font
					(size 1.905 1.4224)
					(thickness 0.1524)
				)
				(justify left)
			)
		)
		(fp_text user "-"
			(at 1.8288 -0.24765 0)
			(unlocked yes)
			(layer "F.Fab")
			(effects
				(font
					(size 1.905 1.4224)
					(thickness 0.1524)
				)
				(justify left)
			)
		)
		(pad "1" smd rect
			(at -1.0922 0 180)
			(size 0.8128 0.8636)
			(layers "F.Cu" "F.Mask" "F.Paste")
			(net "FAN_2_TACH_IL_R")
		)
		(pad "2" smd rect
			(at 1.0922 0)
			(size 0.8128 0.8636)
			(layers "F.Cu" "F.Mask" "F.Paste")
			(net "FAN_2_TACH_IL_D")
		)
	)
	(footprint ""
		(layer "F.Cu")
		(at 4.191 -167.64 180)
		(property "Reference" "R105"
			(at 0 0 180)
			(layer "F.SilkS")
			(hide yes)
			(effects
				(font
					(size 1.27 1.27)
				)
			)
		)
		(property "Value" ""
			(at 0 0 180)
			(layer "F.Fab")
			(effects
				(font
					(size 1.27 1.27)
				)
			)
		)
		(duplicate_pad_numbers_are_jumpers no)
		(fp_line
			(start 0.7874 0.4064)
			(end -0.7874 0.4064)
			(stroke
				(width 0.1524)
				(type default)
			)
			(layer "F.SilkS")
		)
		(fp_line
			(start 0.7874 -0.4064)
			(end 0.7874 0.4064)
			(stroke
				(width 0.1524)
				(type default)
			)
			(layer "F.SilkS")
		)
		(fp_line
			(start -0.7874 0.4064)
			(end -0.7874 -0.4064)
			(stroke
				(width 0.1524)
				(type default)
			)
			(layer "F.SilkS")
		)
		(fp_line
			(start -0.7874 -0.4064)
			(end 0.7874 -0.4064)
			(stroke
				(width 0.1524)
				(type default)
			)
			(layer "F.SilkS")
		)
		(fp_line
			(start 0.67945 0.3048)
			(end 0.120396 0.3048)
			(stroke
				(width 0.1)
				(type default)
			)
			(layer "F.Fab")
		)
		(fp_line
			(start 0.67945 -0.3048)
			(end 0.67945 0.3048)
			(stroke
				(width 0.1)
				(type default)
			)
			(layer "F.Fab")
		)
		(fp_line
			(start 0.12065 -0.2794)
			(end 0.12065 -0.3048)
			(stroke
				(width 0.1)
				(type default)
			)
			(layer "F.Fab")
		)
		(fp_line
			(start 0.12065 -0.3048)
			(end 0.67945 -0.3048)
			(stroke
				(width 0.1)
				(type default)
			)
			(layer "F.Fab")
		)
		(fp_line
			(start 0.120396 0.3048)
			(end 0.120396 0.2794)
			(stroke
				(width 0.1)
				(type default)
			)
			(layer "F.Fab")
		)
		(fp_line
			(start 0.120396 0.2794)
			(end -0.12065 0.2794)
			(stroke
				(width 0.1)
				(type default)
			)
			(layer "F.Fab")
		)
		(fp_line
			(start -0.12065 0.3048)
			(end -0.67945 0.3048)
			(stroke
				(width 0.1)
				(type default)
			)
			(layer "F.Fab")
		)
		(fp_line
			(start -0.12065 0.2794)
			(end -0.12065 0.3048)
			(stroke
				(width 0.1)
				(type default)
			)
			(layer "F.Fab")
		)
		(fp_line
			(start -0.12065 -0.2794)
			(end 0.12065 -0.2794)
			(stroke
				(width 0.1)
				(type default)
			)
			(layer "F.Fab")
		)
		(fp_line
			(start -0.12065 -0.305054)
			(end -0.12065 -0.2794)
			(stroke
				(width 0.1)
				(type default)
			)
			(layer "F.Fab")
		)
		(fp_line
			(start -0.67945 0.3048)
			(end -0.67945 -0.305054)
			(stroke
				(width 0.1)
				(type default)
			)
			(layer "F.Fab")
		)
		(fp_line
			(start -0.67945 -0.305054)
			(end -0.12065 -0.305054)
			(stroke
				(width 0.1)
				(type default)
			)
			(layer "F.Fab")
		)
		(pad "1" smd circle
			(at -0.40005 0 180)
			(size 0 0)
			(layers "F.Cu" "F.Mask" "F.Paste")
			(net "FAN_3_PRSNT_BUF_R_N")
		)
		(pad "2" smd circle
			(at 0.40005 0 180)
			(size 0 0)
			(layers "F.Cu" "F.Mask" "F.Paste")
			(net "FAN_3_PRSNT_BUF_N")
		)
	)
)
